(kicad_pcb
	(version 20260206)
	(generator "pcbnew")
	(generator_version "10.0")
	(general
		(thickness 1.6)
		(legacy_teardrops no)
	)
	(paper "A4")
	(title_block
		(title "01162023_DA0F0TEBIF0_F0T_Expander_BD_F_brd_V02_OCP.brd")
		(comment 1 "Grand Teton / footprints 8161-8168 of 9728")
	)
	(layers
		(0 "F.Cu" signal "TOP")
		(4 "In1.Cu" signal "GND")
		(6 "In2.Cu" signal "VCC")
		(8 "In3.Cu" signal "VCC1")
		(10 "In4.Cu" signal "GND1")
		(12 "In5.Cu" signal "IN1")
		(14 "In6.Cu" signal "GND2")
		(16 "In7.Cu" signal "IN2")
		(18 "In8.Cu" signal "GND3")
		(20 "In9.Cu" signal "IN3")
		(22 "In10.Cu" signal "GND4")
		(24 "In11.Cu" signal "IN4")
		(26 "In12.Cu" signal "GND5")
		(28 "In13.Cu" signal "IN5")
		(30 "In14.Cu" signal "GND6")
		(32 "In15.Cu" signal "IN6")
		(34 "In16.Cu" signal "GND7")
		(2 "B.Cu" signal "BOTTOM")
		(9 "F.Adhes" user "F.Adhesive")
		(11 "B.Adhes" user "B.Adhesive")
		(13 "F.Paste" user "Package Geometry/Pastemask Top")
		(15 "B.Paste" user "Package Geometry/Pastemask Bottom")
		(5 "F.SilkS" user "Ref Des/Silkscreen Top")
		(7 "B.SilkS" user "Ref Des/Silkscreen Bottom")
		(1 "F.Mask" user "Board Geometry/Soldermask Top")
		(3 "B.Mask" user "Board Geometry/Soldermask Bottom")
		(17 "Dwgs.User" user "User.Drawings")
		(19 "Cmts.User" user "User.Comments")
		(21 "Eco1.User" user "User.Eco1")
		(23 "Eco2.User" user "User.Eco2")
		(25 "Edge.Cuts" user "Board Geometry/Outline")
		(27 "Margin" user)
		(31 "F.CrtYd" user "Package Geometry/Place Bound Top")
		(29 "B.CrtYd" user "Package Geometry/Place Bound Bottom")
		(35 "F.Fab" user "Ref Des/Assembly Top")
		(33 "B.Fab" user "Ref Des/Assembly Bottom")
	)
	(footprint ""
		(layer "B.Cu")
		(at 120.038368 -321.387978 -90)
		(property "Reference" "R6484"
			(at 0 0 90)
			(layer "B.SilkS")
			(hide yes)
			(effects
				(font
					(size 1.27 1.27)
				)
				(justify mirror)
			)
		)
		(property "Value" ""
			(at 0 0 90)
			(layer "B.Fab")
			(effects
				(font
					(size 1.27 1.27)
				)
				(justify mirror)
			)
		)
		(duplicate_pad_numbers_are_jumpers no)
		(fp_line
			(start -0.7874 0.4064)
			(end 0.7874 0.4064)
			(stroke
				(width 0.1524)
				(type default)
			)
			(layer "B.SilkS")
		)
		(fp_line
			(start 0.7874 0.4064)
			(end 0.7874 -0.4064)
			(stroke
				(width 0.1524)
				(type default)
			)
			(layer "B.SilkS")
		)
		(fp_line
			(start -0.7874 -0.4064)
			(end -0.7874 0.4064)
			(stroke
				(width 0.1524)
				(type default)
			)
			(layer "B.SilkS")
		)
		(fp_line
			(start 0.7874 -0.4064)
			(end -0.7874 -0.4064)
			(stroke
				(width 0.1524)
				(type default)
			)
			(layer "B.SilkS")
		)
		(fp_line
			(start -0.67945 0.3048)
			(end -0.120396 0.3048)
			(stroke
				(width 0.1)
				(type default)
			)
			(layer "B.Fab")
		)
		(fp_line
			(start -0.120396 0.3048)
			(end -0.120396 0.2794)
			(stroke
				(width 0.1)
				(type default)
			)
			(layer "B.Fab")
		)
		(fp_line
			(start 0.12065 0.3048)
			(end 0.67945 0.3048)
			(stroke
				(width 0.1)
				(type default)
			)
			(layer "B.Fab")
		)
		(fp_line
			(start 0.67945 0.3048)
			(end 0.67945 -0.305054)
			(stroke
				(width 0.1)
				(type default)
			)
			(layer "B.Fab")
		)
		(fp_line
			(start -0.120396 0.2794)
			(end 0.12065 0.2794)
			(stroke
				(width 0.1)
				(type default)
			)
			(layer "B.Fab")
		)
		(fp_line
			(start 0.12065 0.2794)
			(end 0.12065 0.3048)
			(stroke
				(width 0.1)
				(type default)
			)
			(layer "B.Fab")
		)
		(fp_line
			(start -0.12065 -0.2794)
			(end -0.12065 -0.3048)
			(stroke
				(width 0.1)
				(type default)
			)
			(layer "B.Fab")
		)
		(fp_line
			(start 0.12065 -0.2794)
			(end -0.12065 -0.2794)
			(stroke
				(width 0.1)
				(type default)
			)
			(layer "B.Fab")
		)
		(fp_line
			(start -0.67945 -0.3048)
			(end -0.67945 0.3048)
			(stroke
				(width 0.1)
				(type default)
			)
			(layer "B.Fab")
		)
		(fp_line
			(start -0.12065 -0.3048)
			(end -0.67945 -0.3048)
			(stroke
				(width 0.1)
				(type default)
			)
			(layer "B.Fab")
		)
		(fp_line
			(start 0.12065 -0.305054)
			(end 0.12065 -0.2794)
			(stroke
				(width 0.1)
				(type default)
			)
			(layer "B.Fab")
		)
		(fp_line
			(start 0.67945 -0.305054)
			(end 0.12065 -0.305054)
			(stroke
				(width 0.1)
				(type default)
			)
			(layer "B.Fab")
		)
		(pad "1" smd circle
			(at 0.40005 0 90)
			(size 0 0)
			(layers "B.Cu" "B.Mask" "B.Paste")
			(net "P0V8_SERDES_VDDA_PEX1")
		)
		(pad "2" smd circle
			(at -0.40005 0 90)
			(size 0 0)
			(layers "B.Cu" "B.Mask" "B.Paste")
			(net "P0V8_SERDES_VDDA_PEX1_C7")
		)
	)
	(footprint ""
		(layer "B.Cu")
		(at 288.99993 -303.499774 -90)
		(property "Reference" "C3262"
			(at 0 0 90)
			(layer "B.SilkS")
			(hide yes)
			(effects
				(font
					(size 1.27 1.27)
				)
				(justify mirror)
			)
		)
		(property "Value" ""
			(at 0 0 90)
			(layer "B.Fab")
			(effects
				(font
					(size 1.27 1.27)
				)
				(justify mirror)
			)
		)
		(duplicate_pad_numbers_are_jumpers no)
		(fp_line
			(start -0.299974 0.150114)
			(end 0.299974 0.150114)
			(stroke
				(width 0.1)
				(type default)
			)
			(layer "B.Fab")
		)
		(fp_line
			(start 0.299974 0.150114)
			(end 0.299974 -0.150114)
			(stroke
				(width 0.1)
				(type default)
			)
			(layer "B.Fab")
		)
		(fp_line
			(start -0.299974 -0.150114)
			(end -0.299974 0.150114)
			(stroke
				(width 0.1)
				(type default)
			)
			(layer "B.Fab")
		)
		(fp_line
			(start 0.299974 -0.150114)
			(end -0.299974 -0.150114)
			(stroke
				(width 0.1)
				(type default)
			)
			(layer "B.Fab")
		)
		(pad "1" smd rect
			(at 0.2667 0 90)
			(size 0.3048 0.381)
			(layers "B.Cu" "B.Mask" "B.Paste")
			(net "P1V25_PEX2")
		)
		(pad "2" smd rect
			(at -0.2667 0 90)
			(size 0.3048 0.381)
			(layers "B.Cu" "B.Mask" "B.Paste")
			(net "GND")
		)
	)
	(footprint ""
		(layer "B.Cu")
		(at 377.587002 -223.733106)
		(property "Reference" "R925"
			(at 0 0 0)
			(layer "B.SilkS")
			(hide yes)
			(effects
				(font
					(size 1.27 1.27)
				)
				(justify mirror)
			)
		)
		(property "Value" ""
			(at 0 0 0)
			(layer "B.Fab")
			(effects
				(font
					(size 1.27 1.27)
				)
				(justify mirror)
			)
		)
		(duplicate_pad_numbers_are_jumpers no)
		(fp_line
			(start -0.7874 -0.4064)
			(end -0.7874 0.4064)
			(stroke
				(width 0.1524)
				(type default)
			)
			(layer "B.SilkS")
		)
		(fp_line
			(start -0.7874 0.4064)
			(end 0.7874 0.4064)
			(stroke
				(width 0.1524)
				(type default)
			)
			(layer "B.SilkS")
		)
		(fp_line
			(start 0.7874 -0.4064)
			(end -0.7874 -0.4064)
			(stroke
				(width 0.1524)
				(type default)
			)
			(layer "B.SilkS")
		)
		(fp_line
			(start 0.7874 0.4064)
			(end 0.7874 -0.4064)
			(stroke
				(width 0.1524)
				(type default)
			)
			(layer "B.SilkS")
		)
		(fp_line
			(start -0.67945 -0.3048)
			(end -0.67945 0.3048)
			(stroke
				(width 0.1)
				(type default)
			)
			(layer "B.Fab")
		)
		(fp_line
			(start -0.67945 0.3048)
			(end -0.120396 0.3048)
			(stroke
				(width 0.1)
				(type default)
			)
			(layer "B.Fab")
		)
		(fp_line
			(start -0.12065 -0.3048)
			(end -0.67945 -0.3048)
			(stroke
				(width 0.1)
				(type default)
			)
			(layer "B.Fab")
		)
		(fp_line
			(start -0.12065 -0.2794)
			(end -0.12065 -0.3048)
			(stroke
				(width 0.1)
				(type default)
			)
			(layer "B.Fab")
		)
		(fp_line
			(start -0.120396 0.2794)
			(end 0.12065 0.2794)
			(stroke
				(width 0.1)
				(type default)
			)
			(layer "B.Fab")
		)
		(fp_line
			(start -0.120396 0.3048)
			(end -0.120396 0.2794)
			(stroke
				(width 0.1)
				(type default)
			)
			(layer "B.Fab")
		)
		(fp_line
			(start 0.12065 -0.305054)
			(end 0.12065 -0.2794)
			(stroke
				(width 0.1)
				(type default)
			)
			(layer "B.Fab")
		)
		(fp_line
			(start 0.12065 -0.2794)
			(end -0.12065 -0.2794)
			(stroke
				(width 0.1)
				(type default)
			)
			(layer "B.Fab")
		)
		(fp_line
			(start 0.12065 0.2794)
			(end 0.12065 0.3048)
			(stroke
				(width 0.1)
				(type default)
			)
			(layer "B.Fab")
		)
		(fp_line
			(start 0.12065 0.3048)
			(end 0.67945 0.3048)
			(stroke
				(width 0.1)
				(type default)
			)
			(layer "B.Fab")
		)
		(fp_line
			(start 0.67945 -0.305054)
			(end 0.12065 -0.305054)
			(stroke
				(width 0.1)
				(type default)
			)
			(layer "B.Fab")
		)
		(fp_line
			(start 0.67945 0.3048)
			(end 0.67945 -0.305054)
			(stroke
				(width 0.1)
				(type default)
			)
			(layer "B.Fab")
		)
		(pad "1" smd circle
			(at 0.40005 0 180)
			(size 0 0)
			(layers "B.Cu" "B.Mask" "B.Paste")
			(net "UART_PEX0_SDB_BUF_RX")
		)
		(pad "2" smd circle
			(at -0.40005 0 180)
			(size 0 0)
			(layers "B.Cu" "B.Mask" "B.Paste")
			(net "P1V8_PEX")
		)
	)
	(footprint ""
		(layer "B.Cu")
		(at 189.049914 -293.99992 180)
		(property "Reference" "C3124"
			(at 0 0 0)
			(layer "B.SilkS")
			(hide yes)
			(effects
				(font
					(size 1.27 1.27)
				)
				(justify mirror)
			)
		)
		(property "Value" ""
			(at 0 0 0)
			(layer "B.Fab")
			(effects
				(font
					(size 1.27 1.27)
				)
				(justify mirror)
			)
		)
		(duplicate_pad_numbers_are_jumpers no)
		(fp_line
			(start 0.299974 0.150114)
			(end 0.299974 -0.150114)
			(stroke
				(width 0.1)
				(type default)
			)
			(layer "B.Fab")
		)
		(fp_line
			(start 0.299974 -0.150114)
			(end -0.299974 -0.150114)
			(stroke
				(width 0.1)
				(type default)
			)
			(layer "B.Fab")
		)
		(fp_line
			(start -0.299974 0.150114)
			(end 0.299974 0.150114)
			(stroke
				(width 0.1)
				(type default)
			)
			(layer "B.Fab")
		)
		(fp_line
			(start -0.299974 -0.150114)
			(end -0.299974 0.150114)
			(stroke
				(width 0.1)
				(type default)
			)
			(layer "B.Fab")
		)
		(pad "1" smd rect
			(at 0.2667 0)
			(size 0.3048 0.381)
			(layers "B.Cu" "B.Mask" "B.Paste")
			(net "P1V25_SERDES_VDDPLL_PEX1")
		)
		(pad "2" smd rect
			(at -0.2667 0)
			(size 0.3048 0.381)
			(layers "B.Cu" "B.Mask" "B.Paste")
			(net "GND")
		)
	)
	(footprint ""
		(layer "B.Cu")
		(at 46.355 -294.4749)
		(property "Reference" "C3044"
			(at 0 0 0)
			(layer "B.SilkS")
			(hide yes)
			(effects
				(font
					(size 1.27 1.27)
				)
				(justify mirror)
			)
		)
		(property "Value" ""
			(at 0 0 0)
			(layer "B.Fab")
			(effects
				(font
					(size 1.27 1.27)
				)
				(justify mirror)
			)
		)
		(duplicate_pad_numbers_are_jumpers no)
		(fp_line
			(start -0.299974 -0.150114)
			(end -0.299974 0.150114)
			(stroke
				(width 0.1)
				(type default)
			)
			(layer "B.Fab")
		)
		(fp_line
			(start -0.299974 0.150114)
			(end 0.299974 0.150114)
			(stroke
				(width 0.1)
				(type default)
			)
			(layer "B.Fab")
		)
		(fp_line
			(start 0.299974 -0.150114)
			(end -0.299974 -0.150114)
			(stroke
				(width 0.1)
				(type default)
			)
			(layer "B.Fab")
		)
		(fp_line
			(start 0.299974 0.150114)
			(end 0.299974 -0.150114)
			(stroke
				(width 0.1)
				(type default)
			)
			(layer "B.Fab")
		)
		(pad "1" smd rect
			(at 0.2667 0 180)
			(size 0.3048 0.381)
			(layers "B.Cu" "B.Mask" "B.Paste")
			(net "PCEPLL4_VDDA18_PEX0")
		)
		(pad "2" smd rect
			(at -0.2667 0 180)
			(size 0.3048 0.381)
			(layers "B.Cu" "B.Mask" "B.Paste")
			(net "GND")
		)
	)
	(footprint ""
		(layer "B.Cu")
		(at 236.927136 -266.873228)
		(property "Reference" "L117"
			(at 0 0 0)
			(layer "B.SilkS")
			(hide yes)
			(effects
				(font
					(size 1.27 1.27)
				)
				(justify mirror)
			)
		)
		(property "Value" ""
			(at 0 0 0)
			(layer "B.Fab")
			(effects
				(font
					(size 1.27 1.27)
				)
				(justify mirror)
			)
		)
		(duplicate_pad_numbers_are_jumpers no)
		(fp_line
			(start -2.248154 -4.9911)
			(end 2.248154 -4.9911)
			(stroke
				(width 0.1524)
				(type default)
			)
			(layer "B.SilkS")
		)
		(fp_line
			(start -2.248154 -1.895094)
			(end -2.248154 -4.9911)
			(stroke
				(width 0.1524)
				(type default)
			)
			(layer "B.SilkS")
		)
		(fp_line
			(start -2.248154 4.9911)
			(end -2.248154 2.06883)
			(stroke
				(width 0.1524)
				(type default)
			)
			(layer "B.SilkS")
		)
		(fp_line
			(start 2.248154 -4.9911)
			(end 2.248154 -1.895094)
			(stroke
				(width 0.1524)
				(type default)
			)
			(layer "B.SilkS")
		)
		(fp_line
			(start 2.248154 2.06883)
			(end 2.248154 4.9911)
			(stroke
				(width 0.1524)
				(type default)
			)
			(layer "B.SilkS")
		)
		(fp_line
			(start 2.248154 4.9911)
			(end -2.248154 4.9911)
			(stroke
				(width 0.1524)
				(type default)
			)
			(layer "B.SilkS")
		)
		(fp_line
			(start -1.700022 -0.899922)
			(end 1.700022 -0.899922)
			(stroke
				(width 0.1)
				(type default)
			)
			(layer "B.Fab")
		)
		(fp_line
			(start -1.700022 0.899922)
			(end -1.700022 -0.899922)
			(stroke
				(width 0.1)
				(type default)
			)
			(layer "B.Fab")
		)
		(fp_line
			(start 1.700022 -0.899922)
			(end 1.700022 0.899922)
			(stroke
				(width 0.1)
				(type default)
			)
			(layer "B.Fab")
		)
		(fp_line
			(start 1.700022 0.899922)
			(end -1.700022 0.899922)
			(stroke
				(width 0.1)
				(type default)
			)
			(layer "B.Fab")
		)
		(pad "1" smd rect
			(at 1.575054 0 180)
			(size 1.1684 9.8044)
			(layers "B.Cu" "B.Mask" "B.Paste")
			(net "P1V25_PEX2")
		)
		(pad "2" smd rect
			(at -1.575054 0 180)
			(size 1.1684 9.8044)
			(layers "B.Cu" "B.Mask" "B.Paste")
			(net "P1V25_SERDES_VDDPLL_PEX2")
		)
	)
	(footprint ""
		(layer "B.Cu")
		(at 266.67968 -80.506316 180)
		(property "Reference" "C2630"
			(at 0 0 0)
			(layer "B.SilkS")
			(hide yes)
			(effects
				(font
					(size 1.27 1.27)
				)
				(justify mirror)
			)
		)
		(property "Value" ""
			(at 0 0 0)
			(layer "B.Fab")
			(effects
				(font
					(size 1.27 1.27)
				)
				(justify mirror)
			)
		)
		(duplicate_pad_numbers_are_jumpers no)
		(fp_line
			(start 1.2954 0.5842)
			(end 1.2954 -0.5842)
			(stroke
				(width 0.1524)
				(type default)
			)
			(layer "B.SilkS")
		)
		(fp_line
			(start 1.2954 -0.5842)
			(end -1.2954 -0.5842)
			(stroke
				(width 0.1524)
				(type default)
			)
			(layer "B.SilkS")
		)
		(fp_line
			(start -1.2954 0.5842)
			(end 1.2954 0.5842)
			(stroke
				(width 0.1524)
				(type default)
			)
			(layer "B.SilkS")
		)
		(fp_line
			(start -1.2954 -0.5842)
			(end -1.2954 0.5842)
			(stroke
				(width 0.1524)
				(type default)
			)
			(layer "B.SilkS")
		)
		(fp_line
			(start 1.1938 0.4064)
			(end 1.1938 -0.4064)
			(stroke
				(width 0.1)
				(type default)
			)
			(layer "B.Fab")
		)
		(fp_line
			(start 1.1938 -0.4064)
			(end 0.8636 -0.4064)
			(stroke
				(width 0.1)
				(type default)
			)
			(layer "B.Fab")
		)
		(fp_line
			(start 0.8636 0.4572)
			(end 0.8636 0.4064)
			(stroke
				(width 0.1)
				(type default)
			)
			(layer "B.Fab")
		)
		(fp_line
			(start 0.8636 0.4064)
			(end 1.1938 0.4064)
			(stroke
				(width 0.1)
				(type default)
			)
			(layer "B.Fab")
		)
		(fp_line
			(start 0.8636 -0.4064)
			(end 0.8636 -0.4572)
			(stroke
				(width 0.1)
				(type default)
			)
			(layer "B.Fab")
		)
		(fp_line
			(start 0.8636 -0.4572)
			(end -0.8636 -0.4572)
			(stroke
				(width 0.1)
				(type default)
			)
			(layer "B.Fab")
		)
		(fp_line
			(start -0.8636 0.4572)
			(end 0.8636 0.4572)
			(stroke
				(width 0.1)
				(type default)
			)
			(layer "B.Fab")
		)
		(fp_line
			(start -0.8636 0.4064)
			(end -0.8636 0.4572)
			(stroke
				(width 0.1)
				(type default)
			)
			(layer "B.Fab")
		)
		(fp_line
			(start -0.8636 -0.4064)
			(end -1.1938 -0.4064)
			(stroke
				(width 0.1)
				(type default)
			)
			(layer "B.Fab")
		)
		(fp_line
			(start -0.8636 -0.4572)
			(end -0.8636 -0.4064)
			(stroke
				(width 0.1)
				(type default)
			)
			(layer "B.Fab")
		)
		(fp_line
			(start -1.1938 0.4064)
			(end -0.8636 0.4064)
			(stroke
				(width 0.1)
				(type default)
			)
			(layer "B.Fab")
		)
		(fp_line
			(start -1.1938 -0.4064)
			(end -1.1938 0.4064)
			(stroke
				(width 0.1)
				(type default)
			)
			(layer "B.Fab")
		)
		(pad "1" smd rect
			(at 0.7366 0 90)
			(size 0.7112 0.8128)
			(layers "B.Cu" "B.Mask" "B.Paste")
			(net "P3V3_CLK_GEN_VDD_CK440")
		)
		(pad "2" smd rect
			(at -0.7366 0 90)
			(size 0.7112 0.8128)
			(layers "B.Cu" "B.Mask" "B.Paste")
			(net "GND")
		)
	)
	(footprint ""
		(layer "B.Cu")
		(at 72.949816 -294.94988 180)
		(property "Reference" "C2949"
			(at 0 0 0)
			(layer "B.SilkS")
			(hide yes)
			(effects
				(font
					(size 1.27 1.27)
				)
				(justify mirror)
			)
		)
		(property "Value" ""
			(at 0 0 0)
			(layer "B.Fab")
			(effects
				(font
					(size 1.27 1.27)
				)
				(justify mirror)
			)
		)
		(duplicate_pad_numbers_are_jumpers no)
		(fp_line
			(start 0.299974 0.150114)
			(end 0.299974 -0.150114)
			(stroke
				(width 0.1)
				(type default)
			)
			(layer "B.Fab")
		)
		(fp_line
			(start 0.299974 -0.150114)
			(end -0.299974 -0.150114)
			(stroke
				(width 0.1)
				(type default)
			)
			(layer "B.Fab")
		)
		(fp_line
			(start -0.299974 0.150114)
			(end 0.299974 0.150114)
			(stroke
				(width 0.1)
				(type default)
			)
			(layer "B.Fab")
		)
		(fp_line
			(start -0.299974 -0.150114)
			(end -0.299974 0.150114)
			(stroke
				(width 0.1)
				(type default)
			)
			(layer "B.Fab")
		)
		(pad "1" smd rect
			(at 0.2667 0)
			(size 0.3048 0.381)
			(layers "B.Cu" "B.Mask" "B.Paste")
			(net "P1V25_SERDES_VDDPLL_PEX0")
		)
		(pad "2" smd rect
			(at -0.2667 0)
			(size 0.3048 0.381)
			(layers "B.Cu" "B.Mask" "B.Paste")
			(net "GND")
		)
	)
)
